# S9S_MB_2U (Grand Teton) — schematic netlist excerpt (pin names and nets, part order shuffled) for the footprints in the layout excerpt that follows; sources: Cadence DE-HDL packaged netlist, KiCad conversion of 03242023_DA0F0TMBIJ0_F0T_Motherboard_J_brd_V01_OCP.brd

D97  Q_LED  IC  pkg SMLF  page 252 : A = LED_P5V_AUX ; C = GND
R1343  Q_RES  10K 1% CHIP  pkg 0402LF  page 201 : A = P1V05_PCH_AUX ; B = FM_PASSWORD_CLEAR_N

(kicad_pcb
	(version 20260206)
	(generator "pcbnew")
	(generator_version "10.0")
	(general
		(thickness 1.6)
		(legacy_teardrops no)
	)
	(paper "A4")
	(title_block
		(title "03242023_DA0F0TMBIJ0_F0T_Motherboard_J_brd_V01_OCP.brd")
		(comment 1 "Grand Teton / footprints 3520-3521 of 6105")
	)
	(layers
		(0 "F.Cu" signal "TOP")
		(4 "In1.Cu" signal "GND")
		(6 "In2.Cu" signal "IN1")
		(8 "In3.Cu" signal "GND1")
		(10 "In4.Cu" signal "IN2")
		(12 "In5.Cu" signal "GND2")
		(14 "In6.Cu" signal "IN3")
		(16 "In7.Cu" signal "GND3")
		(18 "In8.Cu" signal "VCC")
		(20 "In9.Cu" signal "VCC1")
		(22 "In10.Cu" signal "GND4")
		(24 "In11.Cu" signal "IN4")
		(26 "In12.Cu" signal "GND5")
		(28 "In13.Cu" signal "IN5")
		(30 "In14.Cu" signal "GND6")
		(32 "In15.Cu" signal "IN6")
		(34 "In16.Cu" signal "GND7")
		(2 "B.Cu" signal "BOTTOM")
		(9 "F.Adhes" user "F.Adhesive")
		(11 "B.Adhes" user "B.Adhesive")
		(13 "F.Paste" user "Package Geometry/Pastemask Top")
		(15 "B.Paste" user "Package Geometry/Pastemask Bottom")
		(5 "F.SilkS" user "Ref Des/Silkscreen Top")
		(7 "B.SilkS" user "Ref Des/Silkscreen Bottom")
		(1 "F.Mask" user "Board Geometry/Soldermask Top")
		(3 "B.Mask" user "Board Geometry/Soldermask Bottom")
		(17 "Dwgs.User" user "User.Drawings")
		(19 "Cmts.User" user "User.Comments")
		(21 "Eco1.User" user "User.Eco1")
		(23 "Eco2.User" user "User.Eco2")
		(25 "Edge.Cuts" user "Board Geometry/Outline")
		(27 "Margin" user)
		(31 "F.CrtYd" user "Package Geometry/Place Bound Top")
		(29 "B.CrtYd" user "Package Geometry/Place Bound Bottom")
		(35 "F.Fab" user "Ref Des/Assembly Top")
		(33 "B.Fab" user "Ref Des/Assembly Bottom")
	)
	(footprint ""
		(layer "F.Cu")
		(at 112.799876 -79.078836)
		(property "Reference" "D97"
			(at -55.73141 38.649402 90)
			(unlocked yes)
			(layer "F.SilkS")
			(effects
				(font
					(size 0.635 0.4064)
					(thickness 0.1524)
				)
				(justify left)
			)
		)
		(property "Value" ""
			(at 0 0 0)
			(layer "F.Fab")
			(effects
				(font
					(size 1.27 1.27)
				)
			)
		)
		(duplicate_pad_numbers_are_jumpers no)
		(fp_line
			(start -0.90678 0.4826)
			(end -0.90678 -0.4699)
			(stroke
				(width 0.1524)
				(type default)
			)
			(layer "F.SilkS")
		)
		(fp_line
			(start -0.89408 -0.4826)
			(end 0.90678 -0.4826)
			(stroke
				(width 0.1524)
				(type default)
			)
			(layer "F.SilkS")
		)
		(fp_line
			(start -0.79248 -0.4826)
			(end 1.03378 -0.4826)
			(stroke
				(width 0.1524)
				(type default)
			)
			(layer "F.SilkS")
		)
		(fp_line
			(start -0.64008 -0.4826)
			(end 1.16078 -0.4826)
			(stroke
				(width 0.1524)
				(type default)
			)
			(layer "F.SilkS")
		)
		(fp_line
			(start 0.90678 -0.4826)
			(end 0.90678 0.4826)
			(stroke
				(width 0.1524)
				(type default)
			)
			(layer "F.SilkS")
		)
		(fp_line
			(start 0.90678 0.4826)
			(end -0.90678 0.4826)
			(stroke
				(width 0.1524)
				(type default)
			)
			(layer "F.SilkS")
		)
		(fp_line
			(start 1.03378 -0.4826)
			(end 1.03378 0.4826)
			(stroke
				(width 0.1524)
				(type default)
			)
			(layer "F.SilkS")
		)
		(fp_line
			(start 1.03378 0.4826)
			(end -0.79248 0.4826)
			(stroke
				(width 0.1524)
				(type default)
			)
			(layer "F.SilkS")
		)
		(fp_line
			(start 1.16078 -0.4826)
			(end 1.16078 0.4826)
			(stroke
				(width 0.1524)
				(type default)
			)
			(layer "F.SilkS")
		)
		(fp_line
			(start 1.16078 0.4826)
			(end -0.64008 0.4826)
			(stroke
				(width 0.1524)
				(type default)
			)
			(layer "F.SilkS")
		)
		(fp_line
			(start -0.499872 -0.249936)
			(end 0.499872 -0.249936)
			(stroke
				(width 0.1)
				(type default)
			)
			(layer "F.Fab")
		)
		(fp_line
			(start -0.499872 0.249936)
			(end -0.499872 -0.249936)
			(stroke
				(width 0.1)
				(type default)
			)
			(layer "F.Fab")
		)
		(fp_line
			(start 0.499872 -0.249936)
			(end 0.499872 0.249936)
			(stroke
				(width 0.1)
				(type default)
			)
			(layer "F.Fab")
		)
		(fp_line
			(start 0.499872 0.249936)
			(end -0.499872 0.249936)
			(stroke
				(width 0.1)
				(type default)
			)
			(layer "F.Fab")
		)
		(pad "A" smd rect
			(at -0.47498 0)
			(size 0.6096 0.7112)
			(layers "F.Cu" "F.Mask" "F.Paste")
			(net "LED_P5V_AUX")
		)
		(pad "C" smd rect
			(at 0.47498 0)
			(size 0.6096 0.7112)
			(layers "F.Cu" "F.Mask" "F.Paste")
			(net "GND")
		)
	)
	(footprint ""
		(layer "F.Cu")
		(at 298.036996 -43.594274 90)
		(property "Reference" "R1343"
			(at 0 0 90)
			(layer "F.SilkS")
			(hide yes)
			(effects
				(font
					(size 1.27 1.27)
				)
			)
		)
		(property "Value" ""
			(at 0 0 90)
			(layer "F.Fab")
			(effects
				(font
					(size 1.27 1.27)
				)
			)
		)
		(duplicate_pad_numbers_are_jumpers no)
		(fp_line
			(start 0.7874 -0.4064)
			(end 0.7874 0.4064)
			(stroke
				(width 0.1524)
				(type default)
			)
			(layer "F.SilkS")
		)
		(fp_line
			(start -0.7874 -0.4064)
			(end 0.7874 -0.4064)
			(stroke
				(width 0.1524)
				(type default)
			)
			(layer "F.SilkS")
		)
		(fp_line
			(start 0.7874 0.4064)
			(end -0.7874 0.4064)
			(stroke
				(width 0.1524)
				(type default)
			)
			(layer "F.SilkS")
		)
		(fp_line
			(start -0.7874 0.4064)
			(end -0.7874 -0.4064)
			(stroke
				(width 0.1524)
				(type default)
			)
			(layer "F.SilkS")
		)
		(fp_line
			(start -0.12065 -0.305054)
			(end -0.12065 -0.2794)
			(stroke
				(width 0.1)
				(type default)
			)
			(layer "F.Fab")
		)
		(fp_line
			(start -0.67945 -0.305054)
			(end -0.12065 -0.305054)
			(stroke
				(width 0.1)
				(type default)
			)
			(layer "F.Fab")
		)
		(fp_line
			(start 0.67945 -0.3048)
			(end 0.67945 0.3048)
			(stroke
				(width 0.1)
				(type default)
			)
			(layer "F.Fab")
		)
		(fp_line
			(start 0.12065 -0.3048)
			(end 0.67945 -0.3048)
			(stroke
				(width 0.1)
				(type default)
			)
			(layer "F.Fab")
		)
		(fp_line
			(start 0.12065 -0.2794)
			(end 0.12065 -0.3048)
			(stroke
				(width 0.1)
				(type default)
			)
			(layer "F.Fab")
		)
		(fp_line
			(start -0.12065 -0.2794)
			(end 0.12065 -0.2794)
			(stroke
				(width 0.1)
				(type default)
			)
			(layer "F.Fab")
		)
		(fp_line
			(start 0.120396 0.2794)
			(end -0.12065 0.2794)
			(stroke
				(width 0.1)
				(type default)
			)
			(layer "F.Fab")
		)
		(fp_line
			(start -0.12065 0.2794)
			(end -0.12065 0.3048)
			(stroke
				(width 0.1)
				(type default)
			)
			(layer "F.Fab")
		)
		(fp_line
			(start 0.67945 0.3048)
			(end 0.120396 0.3048)
			(stroke
				(width 0.1)
				(type default)
			)
			(layer "F.Fab")
		)
		(fp_line
			(start 0.120396 0.3048)
			(end 0.120396 0.2794)
			(stroke
				(width 0.1)
				(type default)
			)
			(layer "F.Fab")
		)
		(fp_line
			(start -0.12065 0.3048)
			(end -0.67945 0.3048)
			(stroke
				(width 0.1)
				(type default)
			)
			(layer "F.Fab")
		)
		(fp_line
			(start -0.67945 0.3048)
			(end -0.67945 -0.305054)
			(stroke
				(width 0.1)
				(type default)
			)
			(layer "F.Fab")
		)
		(pad "1" smd circle
			(at -0.40005 0 90)
			(size 0 0)
			(layers "F.Cu" "F.Mask" "F.Paste")
			(net "P1V05_PCH_AUX")
		)
		(pad "2" smd circle
			(at 0.40005 0 90)
			(size 0 0)
			(layers "F.Cu" "F.Mask" "F.Paste")
			(net "FM_PASSWORD_CLEAR_N")
		)
	)
)
